FILE_TYPE=LIBRARY_PARTS;
primitive 'TTL3126','TTL3126_SOIC','TTL3126_SOICLF','TTL3126_SM','TTL3126_SMLF';
  pin
    'OE'<0>:
      PIN_NUMBER='(1,4,10,13)';
      INPUT_LOAD='(-0.01,0.01)';
    'A'<0>:
      PIN_NUMBER='(2,5,9,12)';
      INPUT_LOAD='(-0.01,0.01)';
      OUTPUT_LOAD='(1.00,-1.00)';
      OUTPUT_TYPE='(TS,TS)';
      BIDIRECTIONAL='TRUE';
    'B'<0>:
      PIN_NUMBER='(3,6,8,11)';
      INPUT_LOAD='(-0.01,0.01)';
      OUTPUT_LOAD='(1.00,-1.00)';
      OUTPUT_TYPE='(TS,TS)';
      BIDIRECTIONAL='TRUE';
  end_pin;
  body
    POWER_PINS='(VCC:14)';
    POWER_PINS='(GND:7)';
    PART_NAME='TTL3126';
  end_body;
end_primitive;
primitive 'TTL3126_QFNLF';
  pin
    'OE'<0>:
      PIN_NUMBER='(1,4,10,13)';
      INPUT_LOAD='(-0.01,0.01)';
    'A'<0>:
      PIN_NUMBER='(2,5,9,12)';
      INPUT_LOAD='(-0.01,0.01)';
      OUTPUT_LOAD='(1.00,-1.00)';
      OUTPUT_TYPE='(TS,TS)';
      BIDIRECTIONAL='TRUE';
    'B'<0>:
      PIN_NUMBER='(3,6,8,11)';
      INPUT_LOAD='(-0.01,0.01)';
      OUTPUT_LOAD='(1.00,-1.00)';
      OUTPUT_TYPE='(TS,TS)';
      BIDIRECTIONAL='TRUE';
  end_pin;
  body
    POWER_PINS='(VCC:14)';
    POWER_PINS='(GND:7,15)';
    PART_NAME='TTL3126';
  end_body;
end_primitive;

END.
